# BASEBOARD_FAB2 (Tioga Pass) — schematic netlist excerpt (pin names and nets, part order shuffled) for the footprints in the layout excerpt that follows; sources: Cadence DE-HDL packaged netlist, KiCad conversion of Wiwynn_Tioga_Pass_MB.brd

R25W11  120R2F-GP  1%  pkg RCL_GP  page 151 : \1\ = GND ; \2\ = BMC_M_BG0

U4C2  GTL2014  IC  pkg SM  page 96
  DIR  = PU_GTL2014_2_DIR
  B0  = PWRGD_CPU1_DRAMPWROK_KLM_G
  B1  = PWRGD_CPU1_DRAMPWROK_GHJ_G
  VREF  = PD_GTL2014_2_VREF
  B2  = RST_CPU1_G_N
  B3  = PWRGD_CPU1_G
  GND(0)  = GND
  GND(1)  = GND
  A3  = PWRGD_CPU1_LVC3
  A2  = RST_CPU1_LVC3_N
  GND(2)  = GND
  A1  = PWRGD_DRAMPWRGD
  A0  = PWRGD_DRAMPWRGD
  VCC  = P3V3_STBY

(kicad_pcb
	(version 20260206)
	(generator "pcbnew")
	(generator_version "10.0")
	(general
		(thickness 1.6)
		(legacy_teardrops no)
	)
	(paper "A4")
	(title_block
		(title "Wiwynn_Tioga_Pass_MB.brd")
		(comment 1 "Tioga Pass / footprints 745-746 of 4770")
	)
	(layers
		(0 "F.Cu" signal "TOP")
		(4 "In1.Cu" signal "L2GND")
		(6 "In2.Cu" signal "L3")
		(8 "In3.Cu" signal "L4GND")
		(10 "In4.Cu" signal "L5")
		(12 "In5.Cu" signal "L6GND")
		(14 "In6.Cu" signal "L7VCC")
		(16 "In7.Cu" signal "L8VCC")
		(18 "In8.Cu" signal "L9GND")
		(20 "In9.Cu" signal "L10")
		(22 "In10.Cu" signal "L11GND")
		(24 "In11.Cu" signal "L12")
		(26 "In12.Cu" signal "L13GND")
		(2 "B.Cu" signal "BOTTOM")
		(9 "F.Adhes" user "F.Adhesive")
		(11 "B.Adhes" user "B.Adhesive")
		(13 "F.Paste" user "Package Geometry/Pastemask Top")
		(15 "B.Paste" user "Package Geometry/Pastemask Bottom")
		(5 "F.SilkS" user "Ref Des/Silkscreen Top")
		(7 "B.SilkS" user "Ref Des/Silkscreen Bottom")
		(1 "F.Mask" user "Board Geometry/Soldermask Top")
		(3 "B.Mask" user "Board Geometry/Soldermask Bottom")
		(17 "Dwgs.User" user "User.Drawings")
		(19 "Cmts.User" user "User.Comments")
		(21 "Eco1.User" user "User.Eco1")
		(23 "Eco2.User" user "User.Eco2")
		(25 "Edge.Cuts" user "Board Geometry/Outline")
		(27 "Margin" user)
		(31 "F.CrtYd" user "Package Geometry/Place Bound Top")
		(29 "B.CrtYd" user "Package Geometry/Place Bound Bottom")
		(35 "F.Fab" user "Ref Des/Assembly Top")
		(33 "B.Fab" user "Ref Des/Assembly Bottom")
	)
	(footprint ""
		(layer "F.Cu")
		(at 449.69938 -33.5915 90)
		(property "Reference" "R25W11"
			(at 0 0 90)
			(layer "F.SilkS")
			(hide yes)
			(effects
				(font
					(size 1.27 1.27)
				)
			)
		)
		(property "Value" "*"
			(at 0.064008 -4.108196 90)
			(unlocked yes)
			(layer "F.Fab")
			(hide yes)
			(effects
				(font
					(size 1.27 1.016)
					(thickness 0.1524)
				)
			)
		)
		(property "Device Type" "120R2F-GP_RCL_GP-120R2F-GP,64.A"
			(at 0.064008 -5.632196 90)
			(unlocked yes)
			(layer "F.Fab")
			(hide yes)
			(effects
				(font
					(size 1.27 1.016)
					(thickness 0.1524)
				)
			)
		)
		(duplicate_pad_numbers_are_jumpers no)
		(fp_line
			(start 0.508 -0.9398)
			(end -0.508 -0.9398)
			(stroke
				(width 0.1524)
				(type default)
			)
			(layer "F.SilkS")
		)
		(fp_line
			(start -0.508 -0.9398)
			(end -0.508 0.9398)
			(stroke
				(width 0.1524)
				(type default)
			)
			(layer "F.SilkS")
		)
		(fp_rect
			(start -0.508 0.9398)
			(end 0.508 -0.9398)
			(stroke
				(width 0)
				(type default)
			)
			(fill no)
			(layer "F.CrtYd")
		)
		(fp_rect
			(start -0.508 0.9398)
			(end 0.508 -0.9398)
			(stroke
				(width 0)
				(type default)
			)
			(fill no)
			(layer "F.Fab")
		)
		(pad "1" smd custom
			(at 0 -0.4445 90)
			(size 0.1397 0.1397)
			(layers "F.Cu" "F.Mask" "F.Paste")
			(net "GND")
			(options
				(clearance outline)
				(anchor circle)
			)
			(primitives
				(gr_poly
					(pts
						(arc
							(start -0.1778 -0.2794)
							(mid -0.249642 -0.249642)
							(end -0.2794 -0.1778)
						)
						(arc
							(start -0.2794 0.1778)
							(mid -0.249642 0.249642)
							(end -0.1778 0.2794)
						)
						(arc
							(start 0.1778 0.2794)
							(mid 0.249642 0.249642)
							(end 0.2794 0.1778)
						)
						(arc
							(start 0.2794 -0.1778)
							(mid 0.249642 -0.249642)
							(end 0.1778 -0.2794)
						)
					)
					(width 0)
					(fill yes)
				)
			)
		)
		(pad "2" smd custom
			(at 0 0.4445 90)
			(size 0.1397 0.1397)
			(layers "F.Cu" "F.Mask" "F.Paste")
			(net "BMC_M_BG0")
			(options
				(clearance outline)
				(anchor circle)
			)
			(primitives
				(gr_poly
					(pts
						(arc
							(start -0.1778 -0.2794)
							(mid -0.249642 -0.249642)
							(end -0.2794 -0.1778)
						)
						(arc
							(start -0.2794 0.1778)
							(mid -0.249642 0.249642)
							(end -0.1778 0.2794)
						)
						(arc
							(start 0.1778 0.2794)
							(mid 0.249642 0.249642)
							(end 0.2794 0.1778)
						)
						(arc
							(start 0.2794 -0.1778)
							(mid 0.249642 -0.249642)
							(end 0.1778 -0.2794)
						)
					)
					(width 0)
					(fill yes)
				)
			)
		)
	)
	(footprint ""
		(layer "F.Cu")
		(at 172.681138 -96.310704 90)
		(property "Reference" "U4C2"
			(at -2.076704 5.272532 90)
			(unlocked yes)
			(layer "F.SilkS")
			(effects
				(font
					(size 0.7874 0.5842)
					(thickness 0.1524)
				)
				(justify left)
			)
		)
		(property "Value" ""
			(at 0 0 90)
			(layer "F.Fab")
			(effects
				(font
					(size 1.27 1.27)
				)
			)
		)
		(duplicate_pad_numbers_are_jumpers no)
		(fp_line
			(start 4.4323 -0.64008)
			(end 4.4323 4.52628)
			(stroke
				(width 0.1524)
				(type default)
			)
			(layer "F.SilkS")
		)
		(fp_line
			(start 2.667 -0.64008)
			(end 2.667 0.49022)
			(stroke
				(width 0.1524)
				(type default)
			)
			(layer "F.SilkS")
		)
		(fp_line
			(start 1.5367 -0.64008)
			(end 4.4323 -0.64008)
			(stroke
				(width 0.1524)
				(type default)
			)
			(layer "F.SilkS")
		)
		(fp_line
			(start 3.302 0.49022)
			(end 3.302 -0.64008)
			(stroke
				(width 0.1524)
				(type default)
			)
			(layer "F.SilkS")
		)
		(fp_line
			(start 2.667 0.49022)
			(end 3.302 0.49022)
			(stroke
				(width 0.1524)
				(type default)
			)
			(layer "F.SilkS")
		)
		(fp_line
			(start 4.4323 4.52628)
			(end 1.5367 4.52628)
			(stroke
				(width 0.1524)
				(type default)
			)
			(layer "F.SilkS")
		)
		(fp_line
			(start 1.5367 4.52628)
			(end 1.5367 -0.64008)
			(stroke
				(width 0.1524)
				(type default)
			)
			(layer "F.SilkS")
		)
		(fp_circle
			(center -1.612138 -0.684784)
			(end -1.612138 -0.557784)
			(stroke
				(width 0.254)
				(type default)
			)
			(fill no)
			(layer "F.SilkS")
		)
		(fp_poly
			(pts
				(xy 0.7366 4.54152) (xy 0.7366 -0.64008) (xy 4.7244 -0.64008) (xy 5.2324 -0.64008) (xy 5.2324 4.54152)
				(xy 4.7244 4.54152)
			)
			(stroke
				(width 0)
				(type default)
			)
			(fill no)
			(layer "F.CrtYd")
		)
		(fp_line
			(start 5.2324 -0.64008)
			(end 5.2324 4.54152)
			(stroke
				(width 0.1)
				(type default)
			)
			(layer "F.Fab")
		)
		(fp_line
			(start 2.667 -0.64008)
			(end 2.667 0.49022)
			(stroke
				(width 0.1)
				(type default)
			)
			(layer "F.Fab")
		)
		(fp_line
			(start 0.7366 -0.64008)
			(end 5.2324 -0.64008)
			(stroke
				(width 0.1)
				(type default)
			)
			(layer "F.Fab")
		)
		(fp_line
			(start 3.302 0.49022)
			(end 3.302 -0.64008)
			(stroke
				(width 0.1)
				(type default)
			)
			(layer "F.Fab")
		)
		(fp_line
			(start 2.667 0.49022)
			(end 3.302 0.49022)
			(stroke
				(width 0.1)
				(type default)
			)
			(layer "F.Fab")
		)
		(fp_line
			(start 5.2324 4.54152)
			(end 0.7366 4.54152)
			(stroke
				(width 0.1)
				(type default)
			)
			(layer "F.Fab")
		)
		(fp_line
			(start 0.7366 4.54152)
			(end 0.7366 -0.64008)
			(stroke
				(width 0.1)
				(type default)
			)
			(layer "F.Fab")
		)
		(fp_circle
			(center -1.612138 -0.684784)
			(end -1.612138 -0.557784)
			(stroke
				(width 0.635)
				(type default)
			)
			(fill no)
			(layer "F.Fab")
		)
		(pad "1" smd rect
			(at 0 0 90)
			(size 2.159 0.381)
			(layers "F.Cu" "F.Mask" "F.Paste")
			(net "PU_GTL2014_2_DIR")
		)
		(pad "2" smd rect
			(at 0 0.65024 90)
			(size 2.159 0.381)
			(layers "F.Cu" "F.Mask" "F.Paste")
			(net "PWRGD_CPU1_DRAMPWROK_KLM_G")
		)
		(pad "3" smd rect
			(at 0 1.30048 90)
			(size 2.159 0.381)
			(layers "F.Cu" "F.Mask" "F.Paste")
			(net "PWRGD_CPU1_DRAMPWROK_GHJ_G")
		)
		(pad "4" smd rect
			(at 0 1.95072 90)
			(size 2.159 0.381)
			(layers "F.Cu" "F.Mask" "F.Paste")
			(net "PD_GTL2014_2_VREF")
		)
		(pad "5" smd rect
			(at 0 2.60096 90)
			(size 2.159 0.381)
			(layers "F.Cu" "F.Mask" "F.Paste")
			(net "RST_CPU1_G_N")
		)
		(pad "6" smd rect
			(at 0 3.2512 90)
			(size 2.159 0.381)
			(layers "F.Cu" "F.Mask" "F.Paste")
			(net "PWRGD_CPU1_G")
		)
		(pad "7" smd rect
			(at 0 3.90144 90)
			(size 2.159 0.381)
			(layers "F.Cu" "F.Mask" "F.Paste")
			(net "GND")
		)
		(pad "8" smd rect
			(at 5.969 3.90144 90)
			(size 2.159 0.381)
			(layers "F.Cu" "F.Mask" "F.Paste")
			(net "GND")
		)
		(pad "9" smd rect
			(at 5.969 3.2512 90)
			(size 2.159 0.381)
			(layers "F.Cu" "F.Mask" "F.Paste")
			(net "PWRGD_CPU1_LVC3")
		)
		(pad "10" smd rect
			(at 5.969 2.60096 90)
			(size 2.159 0.381)
			(layers "F.Cu" "F.Mask" "F.Paste")
			(net "RST_CPU1_LVC3_N")
		)
		(pad "11" smd rect
			(at 5.969 1.95072 90)
			(size 2.159 0.381)
			(layers "F.Cu" "F.Mask" "F.Paste")
			(net "GND")
		)
		(pad "12" smd rect
			(at 5.969 1.30048 90)
			(size 2.159 0.381)
			(layers "F.Cu" "F.Mask" "F.Paste")
			(net "PWRGD_DRAMPWRGD")
		)
		(pad "13" smd rect
			(at 5.969 0.65024 90)
			(size 2.159 0.381)
			(layers "F.Cu" "F.Mask" "F.Paste")
			(net "PWRGD_DRAMPWRGD")
		)
		(pad "14" smd rect
			(at 5.969 0 90)
			(size 2.159 0.381)
			(layers "F.Cu" "F.Mask" "F.Paste")
			(net "P3V3_STBY")
		)
	)
)
